# BASEBOARD_FAB2 (Tioga Pass) — schematic netlist excerpt (pin names and nets, part order shuffled) for the footprints in the layout excerpt that follows; sources: Cadence DE-HDL packaged netlist, KiCad conversion of Wiwynn_Tioga_Pass_MB.brd

T1P31  TPAD-SE-2P-GP  pkg DISCRET-GA1  page 256 : \1\ = L1_50OHM_6INCH ; GND1 = GND

Q12W1  BSL308C-H6327-GP  pkg DISCRET-GB1  page 197
  \gate#1\  = PWRGD_PVDDQ_ABC
  \source#2\  = P12V_NVDIMM_ABC
  \gate#3\  = PWRGD_PVDDQ_ABC_N
  \drain#4\  = P12V_NVDIMM_ABC_D
  \source#5\  = GND
  \drain#6\  = PWRGD_PVDDQ_ABC_N

(kicad_pcb
	(version 20260206)
	(generator "pcbnew")
	(generator_version "10.0")
	(general
		(thickness 1.6)
		(legacy_teardrops no)
	)
	(paper "A4")
	(title_block
		(title "Wiwynn_Tioga_Pass_MB.brd")
		(comment 1 "Tioga Pass / footprints 686-687 of 4770")
	)
	(layers
		(0 "F.Cu" signal "TOP")
		(4 "In1.Cu" signal "L2GND")
		(6 "In2.Cu" signal "L3")
		(8 "In3.Cu" signal "L4GND")
		(10 "In4.Cu" signal "L5")
		(12 "In5.Cu" signal "L6GND")
		(14 "In6.Cu" signal "L7VCC")
		(16 "In7.Cu" signal "L8VCC")
		(18 "In8.Cu" signal "L9GND")
		(20 "In9.Cu" signal "L10")
		(22 "In10.Cu" signal "L11GND")
		(24 "In11.Cu" signal "L12")
		(26 "In12.Cu" signal "L13GND")
		(2 "B.Cu" signal "BOTTOM")
		(9 "F.Adhes" user "F.Adhesive")
		(11 "B.Adhes" user "B.Adhesive")
		(13 "F.Paste" user "Package Geometry/Pastemask Top")
		(15 "B.Paste" user "Package Geometry/Pastemask Bottom")
		(5 "F.SilkS" user "Ref Des/Silkscreen Top")
		(7 "B.SilkS" user "Ref Des/Silkscreen Bottom")
		(1 "F.Mask" user "Board Geometry/Soldermask Top")
		(3 "B.Mask" user "Board Geometry/Soldermask Bottom")
		(17 "Dwgs.User" user "User.Drawings")
		(19 "Cmts.User" user "User.Comments")
		(21 "Eco1.User" user "User.Eco1")
		(23 "Eco2.User" user "User.Eco2")
		(25 "Edge.Cuts" user "Board Geometry/Outline")
		(27 "Margin" user)
		(31 "F.CrtYd" user "Package Geometry/Place Bound Top")
		(29 "B.CrtYd" user "Package Geometry/Place Bound Bottom")
		(35 "F.Fab" user "Ref Des/Assembly Top")
		(33 "B.Fab" user "Ref Des/Assembly Bottom")
	)
	(footprint ""
		(layer "F.Cu")
		(at 181.60873 -24.431752 90)
		(property "Reference" "Q12W1"
			(at 0 0 90)
			(layer "F.SilkS")
			(hide yes)
			(effects
				(font
					(size 1.27 1.27)
				)
			)
		)
		(property "Value" "*"
			(at -4.572 -7.6835 90)
			(unlocked yes)
			(layer "F.Fab")
			(hide yes)
			(effects
				(font
					(size 1.27 1.016)
					(thickness 0.1524)
				)
			)
		)
		(property "Device Type" "BSL308C-H6327-GP_DISCRET-GB1-BA"
			(at -4.572 -9.2075 90)
			(unlocked yes)
			(layer "F.Fab")
			(hide yes)
			(effects
				(font
					(size 1.27 1.016)
					(thickness 0.1524)
				)
			)
		)
		(duplicate_pad_numbers_are_jumpers no)
		(fp_line
			(start 1.102868 -0.081534)
			(end 1.102868 0.081534)
			(stroke
				(width 0.1524)
				(type default)
			)
			(layer "F.SilkS")
		)
		(fp_line
			(start -1.8796 -0.081534)
			(end 1.102868 -0.081534)
			(stroke
				(width 0.1524)
				(type default)
			)
			(layer "F.SilkS")
		)
		(fp_line
			(start -1.8796 -0.081534)
			(end -1.524 0)
			(stroke
				(width 0.1524)
				(type default)
			)
			(layer "F.SilkS")
		)
		(fp_line
			(start -1.524 0)
			(end -1.8796 0.081534)
			(stroke
				(width 0.1524)
				(type default)
			)
			(layer "F.SilkS")
		)
		(fp_line
			(start 1.102868 0.081534)
			(end -1.8796 0.081534)
			(stroke
				(width 0.1524)
				(type default)
			)
			(layer "F.SilkS")
		)
		(fp_line
			(start -1.8796 0.081534)
			(end -1.8796 -0.081534)
			(stroke
				(width 0.1524)
				(type default)
			)
			(layer "F.SilkS")
		)
		(fp_line
			(start -1.7018 0.3048)
			(end -1.7018 1.8796)
			(stroke
				(width 0.508)
				(type default)
			)
			(layer "F.SilkS")
		)
		(fp_poly
			(pts
				(xy -1.179068 0.081534) (xy -1.179068 -0.081534) (xy 1.102868 -0.081534) (xy 1.102868 0.081534)
			)
			(stroke
				(width 0)
				(type default)
			)
			(fill yes)
			(layer "F.SilkS")
		)
		(fp_rect
			(start -1.4478 1.2446)
			(end 1.4478 -1.2446)
			(stroke
				(width 0)
				(type default)
			)
			(fill no)
			(layer "F.CrtYd")
		)
		(fp_poly
			(pts
				(xy -1.4478 -1.23952) (xy -1.9558 -1.23952) (xy -1.9558 2.1336) (xy 1.9558 2.1336) (xy 1.9558 -2.1336)
				(xy -1.9558 -2.1336) (xy -1.9558 -1.2446) (xy 1.4478 -1.2446) (xy 1.4478 1.2446) (xy -1.4478 1.2446)
			)
			(stroke
				(width 0)
				(type default)
			)
			(fill no)
			(layer "F.CrtYd")
		)
		(fp_rect
			(start -1.9558 2.1336)
			(end 1.9558 -2.1336)
			(stroke
				(width 0)
				(type default)
			)
			(fill no)
			(layer "F.Fab")
		)
		(pad "1" smd rect
			(at -0.950468 0.995934 90)
			(size 0.4572 1.27)
			(layers "F.Cu" "F.Mask" "F.Paste")
			(net "PWRGD_PVDDQ_ABC")
		)
		(pad "2" smd rect
			(at 0 0.995934 90)
			(size 0.4572 1.27)
			(layers "F.Cu" "F.Mask" "F.Paste")
			(net "P12V_NVDIMM_ABC")
		)
		(pad "3" smd rect
			(at 0.950468 0.995934 90)
			(size 0.4572 1.27)
			(layers "F.Cu" "F.Mask" "F.Paste")
			(net "PWRGD_PVDDQ_ABC_N")
		)
		(pad "4" smd rect
			(at 0.950468 -0.995934 90)
			(size 0.4572 1.27)
			(layers "F.Cu" "F.Mask" "F.Paste")
			(net "P12V_NVDIMM_ABC_D")
		)
		(pad "5" smd rect
			(at 0 -0.995934 90)
			(size 0.4572 1.27)
			(layers "F.Cu" "F.Mask" "F.Paste")
			(net "GND")
		)
		(pad "6" smd rect
			(at -0.950468 -0.995934 90)
			(size 0.4572 1.27)
			(layers "F.Cu" "F.Mask" "F.Paste")
			(net "PWRGD_PVDDQ_ABC_N")
		)
	)
	(footprint ""
		(layer "F.Cu")
		(at 9.017 13.2715 -90)
		(property "Reference" "T1P31"
			(at 0 0 270)
			(layer "F.SilkS")
			(hide yes)
			(effects
				(font
					(size 1.27 1.27)
				)
			)
		)
		(property "Value" "*"
			(at 0 -3.44805 270)
			(unlocked yes)
			(layer "F.Fab")
			(hide yes)
			(effects
				(font
					(size 0.889 0.889)
					(thickness 0.1524)
				)
			)
		)
		(property "Device Type" "TPAD-SE-2P-GP_DISCRET-GA1-TPADA"
			(at 0 -4.97205 270)
			(unlocked yes)
			(layer "F.Fab")
			(hide yes)
			(effects
				(font
					(size 0.889 0.889)
					(thickness 0.1524)
				)
			)
		)
		(duplicate_pad_numbers_are_jumpers no)
		(fp_line
			(start -1.016 2.286)
			(end -1.016 -2.286)
			(stroke
				(width 0.1524)
				(type default)
			)
			(layer "F.SilkS")
		)
		(fp_line
			(start 1.016 2.286)
			(end -1.016 2.286)
			(stroke
				(width 0.1524)
				(type default)
			)
			(layer "F.SilkS")
		)
		(fp_line
			(start -1.016 -2.286)
			(end 1.016 -2.286)
			(stroke
				(width 0.1524)
				(type default)
			)
			(layer "F.SilkS")
		)
		(fp_line
			(start 1.016 -2.286)
			(end 1.016 2.286)
			(stroke
				(width 0.1524)
				(type default)
			)
			(layer "F.SilkS")
		)
		(fp_rect
			(start -1.27 2.54)
			(end 1.27 -2.54)
			(stroke
				(width 0)
				(type default)
			)
			(fill no)
			(layer "F.CrtYd")
		)
		(fp_rect
			(start -1.27 2.54)
			(end 1.27 -2.54)
			(stroke
				(width 0)
				(type default)
			)
			(fill no)
			(layer "F.Fab")
		)
		(pad "1" thru_hole circle
			(at 0 -1.27 270)
			(size 1.524 1.524)
			(drill 0.9144)
			(layers "*.Cu" "*.Mask")
			(remove_unused_layers no)
			(net "L1_50OHM_6INCH")
			(clearance -0.0508)
			(thermal_gap 0.127)
			(padstack
				(mode front_inner_back)
				(layer "Inner"
					(shape circle)
					(size 1.1684 1.1684)
					(clearance 0.127)
				)
				(layer "B.Cu"
					(shape circle)
					(size 1.524 1.524)
					(clearance -0.0508)
				)
			)
		)
		(pad "GND1" thru_hole rect
			(at 0 1.27 270)
			(size 1.524 1.524)
			(drill 0.9144)
			(layers "*.Cu" "*.Mask")
			(remove_unused_layers no)
			(net "GND")
			(clearance -0.0508)
			(thermal_gap 0.127)
			(padstack
				(mode front_inner_back)
				(layer "Inner"
					(shape circle)
					(size 1.1684 1.1684)
					(clearance 0.127)
				)
				(layer "B.Cu"
					(shape rect)
					(size 1.524 1.524)
					(clearance -0.0508)
				)
			)
		)
	)
)
